FILE_TYPE=LIBRARY_PARTS;
primitive 'MOSFET_N_GSD';
  pin
    'GATE':
      PIN_NUMBER='(G)';
      INPUT_LOAD='(-0.01,0.01)';
    'SOURCE':
      PIN_NUMBER='(S)';
      BIDIRECTIONAL='TRUE';
      INPUT_LOAD='(-0.01,0.01)';
      OUTPUT_LOAD='(1.0,-1.0)';
    'DRAIN':
      PIN_NUMBER='(D)';
      BIDIRECTIONAL='TRUE';
      INPUT_LOAD='(-0.01,0.01)';
      OUTPUT_LOAD='(1.0,-1.0)';
  end_pin;
  body
    PART_NAME='MOSFET_N_GSD';
    BODY_NAME='MOSFET_N_GSD';
    PHYS_DES_PREFIX='Q';
    CLASS='DISCRETE';
  end_body;
end_primitive;

END.
